(kicad_pcb
	(version 20260206)
	(generator "pcbnew")
	(generator_version "10.0")
	(general
		(thickness 1.6)
		(legacy_teardrops no)
	)
	(paper "A4")
	(title_block
		(title "04192023_DAF0TMB3IC0_F0TG_MB_C_brd_V02_OCP.brd")
		(comment 1 "Grand Teton / footprints 288-293 of 8354")
	)
	(layers
		(0 "F.Cu" signal "TOP")
		(4 "In1.Cu" signal "GND")
		(6 "In2.Cu" signal "IN1")
		(8 "In3.Cu" signal "GND1")
		(10 "In4.Cu" signal "IN2")
		(12 "In5.Cu" signal "GND2")
		(14 "In6.Cu" signal "IN3")
		(16 "In7.Cu" signal "GND3")
		(18 "In8.Cu" signal "VCC")
		(20 "In9.Cu" signal "VCC1")
		(22 "In10.Cu" signal "GND4")
		(24 "In11.Cu" signal "IN4")
		(26 "In12.Cu" signal "GND5")
		(28 "In13.Cu" signal "IN5")
		(30 "In14.Cu" signal "GND6")
		(32 "In15.Cu" signal "IN6")
		(34 "In16.Cu" signal "GND7")
		(2 "B.Cu" signal "BOTTOM")
		(9 "F.Adhes" user "F.Adhesive")
		(11 "B.Adhes" user "B.Adhesive")
		(13 "F.Paste" user "Package Geometry/Pastemask Top")
		(15 "B.Paste" user "Package Geometry/Pastemask Bottom")
		(5 "F.SilkS" user "Ref Des/Silkscreen Top")
		(7 "B.SilkS" user "Ref Des/Silkscreen Bottom")
		(1 "F.Mask" user "Board Geometry/Soldermask Top")
		(3 "B.Mask" user "Board Geometry/Soldermask Bottom")
		(17 "Dwgs.User" user "User.Drawings")
		(19 "Cmts.User" user "User.Comments")
		(21 "Eco1.User" user "User.Eco1")
		(23 "Eco2.User" user "User.Eco2")
		(25 "Edge.Cuts" user "Board Geometry/Outline")
		(27 "Margin" user)
		(31 "F.CrtYd" user "Package Geometry/Place Bound Top")
		(29 "B.CrtYd" user "Package Geometry/Place Bound Bottom")
		(35 "F.Fab" user "Ref Des/Assembly Top")
		(33 "B.Fab" user "Ref Des/Assembly Bottom")
	)
	(footprint ""
		(layer "F.Cu")
		(at 281.659076 -412.452058 90)
		(property "Reference" "L20"
			(at 0 0 90)
			(layer "F.SilkS")
			(hide yes)
			(effects
				(font
					(size 1.27 1.27)
				)
			)
		)
		(property "Value" ""
			(at 0 0 90)
			(layer "F.Fab")
			(effects
				(font
					(size 1.27 1.27)
				)
			)
		)
		(duplicate_pad_numbers_are_jumpers no)
		(fp_line
			(start 1.63576 -0.8128)
			(end 1.63576 0.8128)
			(stroke
				(width 0.1524)
				(type default)
			)
			(layer "F.SilkS")
		)
		(fp_line
			(start -1.63576 -0.8128)
			(end 1.63576 -0.8128)
			(stroke
				(width 0.1524)
				(type default)
			)
			(layer "F.SilkS")
		)
		(fp_line
			(start -1.63576 -0.8128)
			(end -1.63576 0.8128)
			(stroke
				(width 0.1524)
				(type default)
			)
			(layer "F.SilkS")
		)
		(fp_line
			(start 1.63576 0.8128)
			(end -1.63576 0.8128)
			(stroke
				(width 0.1524)
				(type default)
			)
			(layer "F.SilkS")
		)
		(fp_line
			(start 1.560576 -0.738632)
			(end -1.56083 -0.738632)
			(stroke
				(width 0.1)
				(type default)
			)
			(layer "F.Fab")
		)
		(fp_line
			(start -1.56083 -0.738632)
			(end -1.56083 0.7366)
			(stroke
				(width 0.1)
				(type default)
			)
			(layer "F.Fab")
		)
		(fp_line
			(start 1.560576 0.7366)
			(end 1.560576 -0.738632)
			(stroke
				(width 0.1)
				(type default)
			)
			(layer "F.Fab")
		)
		(fp_line
			(start 1.524 0.7366)
			(end 1.560576 0.7366)
			(stroke
				(width 0.1)
				(type default)
			)
			(layer "F.Fab")
		)
		(fp_line
			(start -1.524 0.7366)
			(end 1.524 0.7366)
			(stroke
				(width 0.1)
				(type default)
			)
			(layer "F.Fab")
		)
		(fp_line
			(start -1.56083 0.7366)
			(end -1.524 0.7366)
			(stroke
				(width 0.1)
				(type default)
			)
			(layer "F.Fab")
		)
		(pad "1" smd rect
			(at -0.94996 0 270)
			(size 1.1176 1.3716)
			(layers "F.Cu" "F.Mask" "F.Paste")
			(net "P3V3_AUX")
		)
		(pad "2" smd rect
			(at 0.94996 0 270)
			(size 1.1176 1.3716)
			(layers "F.Cu" "F.Mask" "F.Paste")
			(net "P3V3_9ZXL045_P0_VDD")
		)
	)
	(footprint ""
		(layer "F.Cu")
		(at 419.96106 -351.11309 -90)
		(property "Reference" "PC205_11P0_1"
			(at 0 0 270)
			(layer "F.SilkS")
			(hide yes)
			(effects
				(font
					(size 1.27 1.27)
				)
			)
		)
		(property "Value" ""
			(at 0 0 270)
			(layer "F.Fab")
			(effects
				(font
					(size 1.27 1.27)
				)
			)
		)
		(duplicate_pad_numbers_are_jumpers no)
		(fp_line
			(start -0.7874 0.4064)
			(end -0.7874 -0.4064)
			(stroke
				(width 0.1524)
				(type default)
			)
			(layer "F.SilkS")
		)
		(fp_line
			(start 0.7874 0.4064)
			(end -0.7874 0.4064)
			(stroke
				(width 0.1524)
				(type default)
			)
			(layer "F.SilkS")
		)
		(fp_line
			(start -0.7874 -0.4064)
			(end 0.7874 -0.4064)
			(stroke
				(width 0.1524)
				(type default)
			)
			(layer "F.SilkS")
		)
		(fp_line
			(start 0.7874 -0.4064)
			(end 0.7874 0.4064)
			(stroke
				(width 0.1524)
				(type default)
			)
			(layer "F.SilkS")
		)
		(fp_line
			(start -0.67945 0.3048)
			(end -0.67945 -0.305054)
			(stroke
				(width 0.1)
				(type default)
			)
			(layer "F.Fab")
		)
		(fp_line
			(start -0.12065 0.3048)
			(end -0.67945 0.3048)
			(stroke
				(width 0.1)
				(type default)
			)
			(layer "F.Fab")
		)
		(fp_line
			(start 0.120396 0.3048)
			(end 0.120396 0.2794)
			(stroke
				(width 0.1)
				(type default)
			)
			(layer "F.Fab")
		)
		(fp_line
			(start 0.67945 0.3048)
			(end 0.120396 0.3048)
			(stroke
				(width 0.1)
				(type default)
			)
			(layer "F.Fab")
		)
		(fp_line
			(start -0.12065 0.2794)
			(end -0.12065 0.3048)
			(stroke
				(width 0.1)
				(type default)
			)
			(layer "F.Fab")
		)
		(fp_line
			(start 0.120396 0.2794)
			(end -0.12065 0.2794)
			(stroke
				(width 0.1)
				(type default)
			)
			(layer "F.Fab")
		)
		(fp_line
			(start -0.12065 -0.2794)
			(end 0.12065 -0.2794)
			(stroke
				(width 0.1)
				(type default)
			)
			(layer "F.Fab")
		)
		(fp_line
			(start 0.12065 -0.2794)
			(end 0.12065 -0.3048)
			(stroke
				(width 0.1)
				(type default)
			)
			(layer "F.Fab")
		)
		(fp_line
			(start 0.12065 -0.3048)
			(end 0.67945 -0.3048)
			(stroke
				(width 0.1)
				(type default)
			)
			(layer "F.Fab")
		)
		(fp_line
			(start 0.67945 -0.3048)
			(end 0.67945 0.3048)
			(stroke
				(width 0.1)
				(type default)
			)
			(layer "F.Fab")
		)
		(fp_line
			(start -0.67945 -0.305054)
			(end -0.12065 -0.305054)
			(stroke
				(width 0.1)
				(type default)
			)
			(layer "F.Fab")
		)
		(fp_line
			(start -0.12065 -0.305054)
			(end -0.12065 -0.2794)
			(stroke
				(width 0.1)
				(type default)
			)
			(layer "F.Fab")
		)
		(pad "1" smd circle
			(at -0.40005 0 270)
			(size 0 0)
			(layers "F.Cu" "F.Mask" "F.Paste")
			(net "PVDD11_S3_P0_PVCC")
		)
		(pad "2" smd circle
			(at 0.40005 0 270)
			(size 0 0)
			(layers "F.Cu" "F.Mask" "F.Paste")
			(net "GND")
		)
	)
	(footprint ""
		(layer "F.Cu")
		(at 257.683 -142.367)
		(property "Reference" "R21"
			(at 0 0 0)
			(layer "F.SilkS")
			(hide yes)
			(effects
				(font
					(size 1.27 1.27)
				)
			)
		)
		(property "Value" ""
			(at 0 0 0)
			(layer "F.Fab")
			(effects
				(font
					(size 1.27 1.27)
				)
			)
		)
		(duplicate_pad_numbers_are_jumpers no)
		(fp_line
			(start -0.7874 -0.4064)
			(end 0.7874 -0.4064)
			(stroke
				(width 0.1524)
				(type default)
			)
			(layer "F.SilkS")
		)
		(fp_line
			(start -0.7874 0.4064)
			(end -0.7874 -0.4064)
			(stroke
				(width 0.1524)
				(type default)
			)
			(layer "F.SilkS")
		)
		(fp_line
			(start 0.7874 -0.4064)
			(end 0.7874 0.4064)
			(stroke
				(width 0.1524)
				(type default)
			)
			(layer "F.SilkS")
		)
		(fp_line
			(start 0.7874 0.4064)
			(end -0.7874 0.4064)
			(stroke
				(width 0.1524)
				(type default)
			)
			(layer "F.SilkS")
		)
		(fp_line
			(start -0.67945 -0.305054)
			(end -0.12065 -0.305054)
			(stroke
				(width 0.1)
				(type default)
			)
			(layer "F.Fab")
		)
		(fp_line
			(start -0.67945 0.3048)
			(end -0.67945 -0.305054)
			(stroke
				(width 0.1)
				(type default)
			)
			(layer "F.Fab")
		)
		(fp_line
			(start -0.12065 -0.305054)
			(end -0.12065 -0.2794)
			(stroke
				(width 0.1)
				(type default)
			)
			(layer "F.Fab")
		)
		(fp_line
			(start -0.12065 -0.2794)
			(end 0.12065 -0.2794)
			(stroke
				(width 0.1)
				(type default)
			)
			(layer "F.Fab")
		)
		(fp_line
			(start -0.12065 0.2794)
			(end -0.12065 0.3048)
			(stroke
				(width 0.1)
				(type default)
			)
			(layer "F.Fab")
		)
		(fp_line
			(start -0.12065 0.3048)
			(end -0.67945 0.3048)
			(stroke
				(width 0.1)
				(type default)
			)
			(layer "F.Fab")
		)
		(fp_line
			(start 0.120396 0.2794)
			(end -0.12065 0.2794)
			(stroke
				(width 0.1)
				(type default)
			)
			(layer "F.Fab")
		)
		(fp_line
			(start 0.120396 0.3048)
			(end 0.120396 0.2794)
			(stroke
				(width 0.1)
				(type default)
			)
			(layer "F.Fab")
		)
		(fp_line
			(start 0.12065 -0.3048)
			(end 0.67945 -0.3048)
			(stroke
				(width 0.1)
				(type default)
			)
			(layer "F.Fab")
		)
		(fp_line
			(start 0.12065 -0.2794)
			(end 0.12065 -0.3048)
			(stroke
				(width 0.1)
				(type default)
			)
			(layer "F.Fab")
		)
		(fp_line
			(start 0.67945 -0.3048)
			(end 0.67945 0.3048)
			(stroke
				(width 0.1)
				(type default)
			)
			(layer "F.Fab")
		)
		(fp_line
			(start 0.67945 0.3048)
			(end 0.120396 0.3048)
			(stroke
				(width 0.1)
				(type default)
			)
			(layer "F.Fab")
		)
		(pad "1" smd circle
			(at -0.40005 0)
			(size 0 0)
			(layers "F.Cu" "F.Mask" "F.Paste")
			(net "P3V3_AUX")
		)
		(pad "2" smd circle
			(at 0.40005 0)
			(size 0 0)
			(layers "F.Cu" "F.Mask" "F.Paste")
			(net "SPI_CPU0_LVC3_SCM_D0")
		)
	)
	(footprint ""
		(layer "F.Cu")
		(at 146.304762 -43.03141 180)
		(property "Reference" "R2411"
			(at 0 0 180)
			(layer "F.SilkS")
			(hide yes)
			(effects
				(font
					(size 1.27 1.27)
				)
			)
		)
		(property "Value" ""
			(at 0 0 180)
			(layer "F.Fab")
			(effects
				(font
					(size 1.27 1.27)
				)
			)
		)
		(duplicate_pad_numbers_are_jumpers no)
		(fp_line
			(start 0.7874 0.4064)
			(end -0.7874 0.4064)
			(stroke
				(width 0.1524)
				(type default)
			)
			(layer "F.SilkS")
		)
		(fp_line
			(start 0.7874 -0.4064)
			(end 0.7874 0.4064)
			(stroke
				(width 0.1524)
				(type default)
			)
			(layer "F.SilkS")
		)
		(fp_line
			(start -0.7874 0.4064)
			(end -0.7874 -0.4064)
			(stroke
				(width 0.1524)
				(type default)
			)
			(layer "F.SilkS")
		)
		(fp_line
			(start -0.7874 -0.4064)
			(end 0.7874 -0.4064)
			(stroke
				(width 0.1524)
				(type default)
			)
			(layer "F.SilkS")
		)
		(fp_line
			(start 0.67945 0.3048)
			(end 0.120396 0.3048)
			(stroke
				(width 0.1)
				(type default)
			)
			(layer "F.Fab")
		)
		(fp_line
			(start 0.67945 -0.3048)
			(end 0.67945 0.3048)
			(stroke
				(width 0.1)
				(type default)
			)
			(layer "F.Fab")
		)
		(fp_line
			(start 0.12065 -0.2794)
			(end 0.12065 -0.3048)
			(stroke
				(width 0.1)
				(type default)
			)
			(layer "F.Fab")
		)
		(fp_line
			(start 0.12065 -0.3048)
			(end 0.67945 -0.3048)
			(stroke
				(width 0.1)
				(type default)
			)
			(layer "F.Fab")
		)
		(fp_line
			(start 0.120396 0.3048)
			(end 0.120396 0.2794)
			(stroke
				(width 0.1)
				(type default)
			)
			(layer "F.Fab")
		)
		(fp_line
			(start 0.120396 0.2794)
			(end -0.12065 0.2794)
			(stroke
				(width 0.1)
				(type default)
			)
			(layer "F.Fab")
		)
		(fp_line
			(start -0.12065 0.3048)
			(end -0.67945 0.3048)
			(stroke
				(width 0.1)
				(type default)
			)
			(layer "F.Fab")
		)
		(fp_line
			(start -0.12065 0.2794)
			(end -0.12065 0.3048)
			(stroke
				(width 0.1)
				(type default)
			)
			(layer "F.Fab")
		)
		(fp_line
			(start -0.12065 -0.2794)
			(end 0.12065 -0.2794)
			(stroke
				(width 0.1)
				(type default)
			)
			(layer "F.Fab")
		)
		(fp_line
			(start -0.12065 -0.305054)
			(end -0.12065 -0.2794)
			(stroke
				(width 0.1)
				(type default)
			)
			(layer "F.Fab")
		)
		(fp_line
			(start -0.67945 0.3048)
			(end -0.67945 -0.305054)
			(stroke
				(width 0.1)
				(type default)
			)
			(layer "F.Fab")
		)
		(fp_line
			(start -0.67945 -0.305054)
			(end -0.12065 -0.305054)
			(stroke
				(width 0.1)
				(type default)
			)
			(layer "F.Fab")
		)
		(pad "1" smd circle
			(at -0.40005 0 180)
			(size 0 0)
			(layers "F.Cu" "F.Mask" "F.Paste")
			(net "SMB_M2_P1_1V8AUX_SCL_R")
		)
		(pad "2" smd circle
			(at 0.40005 0 180)
			(size 0 0)
			(layers "F.Cu" "F.Mask" "F.Paste")
			(net "SMB_M2_P1_1V8AUX_SCL")
		)
	)
	(footprint ""
		(layer "F.Cu")
		(at 458.3811 -423.492168)
		(property "Reference" "H27"
			(at 2.5654 2.321052 0)
			(unlocked yes)
			(layer "F.SilkS")
			(effects
				(font
					(size 0.7874 0.5842)
					(thickness 0.1524)
				)
				(justify left)
			)
		)
		(property "Value" ""
			(at 0 0 0)
			(layer "F.Fab")
			(effects
				(font
					(size 1.27 1.27)
				)
			)
		)
		(duplicate_pad_numbers_are_jumpers no)
		(fp_circle
			(center 0 0)
			(end 2.4003 0)
			(stroke
				(width 0.1524)
				(type default)
			)
			(fill no)
			(layer "F.SilkS")
		)
		(fp_circle
			(center 0 0)
			(end 6.5913 0)
			(stroke
				(width 0.1524)
				(type default)
			)
			(fill no)
			(layer "B.SilkS")
		)
		(fp_circle
			(center 0 0)
			(end 6.5913 0)
			(stroke
				(width 0.1)
				(type default)
			)
			(fill no)
			(layer "B.Fab")
		)
		(fp_circle
			(center 0 0)
			(end 2.4003 0)
			(stroke
				(width 0.1)
				(type default)
			)
			(fill no)
			(layer "F.Fab")
		)
		(pad "" np_thru_hole circle
			(at 0 0)
			(size 3.175 3.175)
			(drill 3.175)
			(layers "*.Cu" "*.Mask")
			(clearance 0.381)
			(thermal_gap 0.381)
		)
		(zone
			(layers "F.Cu" "B.Cu" "In1.Cu" "In2.Cu" "In3.Cu" "In4.Cu" "In5.Cu" "In6.Cu"
				"In7.Cu" "In8.Cu" "In9.Cu" "In10.Cu" "In11.Cu" "In12.Cu" "In13.Cu" "In14.Cu"
				"In15.Cu" "In16.Cu"
			)
			(hatch none 0.5)
			(connect_pads
				(clearance 0)
			)
			(min_thickness 0.25)
			(keepout
				(tracks not_allowed)
				(vias allowed)
				(pads allowed)
				(copperpour not_allowed)
				(footprints allowed)
			)
			(placement
				(enabled no)
				(sheetname "")
			)
			(fill
				(thermal_gap 0.5)
				(thermal_bridge_width 0.5)
				(island_removal_mode 0)
			)
			(polygon
				(pts
					(arc
						(start 460.4766 -423.492168)
						(mid 456.2856 -423.492168)
						(end 460.4766 -423.492168)
					)
				)
			)
		)
	)
	(footprint ""
		(layer "F.Cu")
		(at 192.324736 -437.584088)
		(property "Reference" "JP10"
			(at -1.4097 -2.009648 0)
			(unlocked yes)
			(layer "F.SilkS")
			(effects
				(font
					(size 0.7874 0.5842)
					(thickness 0.1524)
				)
				(justify left)
			)
		)
		(property "Value" ""
			(at 0 0 0)
			(layer "F.Fab")
			(effects
				(font
					(size 1.27 1.27)
				)
			)
		)
		(duplicate_pad_numbers_are_jumpers no)
		(fp_line
			(start -1.249934 -1.320038)
			(end 1.249934 -1.320038)
			(stroke
				(width 0.1524)
				(type default)
			)
			(layer "F.SilkS")
		)
		(fp_line
			(start -1.249934 6.400038)
			(end -1.249934 -1.320038)
			(stroke
				(width 0.1524)
				(type default)
			)
			(layer "F.SilkS")
		)
		(fp_line
			(start 1.249934 -1.320038)
			(end 1.249934 6.400038)
			(stroke
				(width 0.1524)
				(type default)
			)
			(layer "F.SilkS")
		)
		(fp_line
			(start 1.249934 6.400038)
			(end -1.249934 6.400038)
			(stroke
				(width 0.1524)
				(type default)
			)
			(layer "F.SilkS")
		)
		(fp_poly
			(pts
				(xy -2.5654 0.556514) (xy -2.5654 -0.556514) (xy -1.452372 0)
			)
			(stroke
				(width 0)
				(type default)
			)
			(fill yes)
			(layer "F.SilkS")
		)
		(fp_line
			(start -1.249934 -1.320038)
			(end 1.249934 -1.320038)
			(stroke
				(width 0.1)
				(type default)
			)
			(layer "F.Fab")
		)
		(fp_line
			(start -1.249934 6.400038)
			(end -1.249934 -1.320038)
			(stroke
				(width 0.1)
				(type default)
			)
			(layer "F.Fab")
		)
		(fp_line
			(start 1.249934 -1.320038)
			(end 1.249934 6.400038)
			(stroke
				(width 0.1)
				(type default)
			)
			(layer "F.Fab")
		)
		(fp_line
			(start 1.249934 6.400038)
			(end -1.249934 6.400038)
			(stroke
				(width 0.1)
				(type default)
			)
			(layer "F.Fab")
		)
		(fp_poly
			(pts
				(xy -2.5654 -0.556514) (xy -1.452372 0) (xy -2.5654 0.556514)
			)
			(stroke
				(width 0)
				(type default)
			)
			(fill yes)
			(layer "F.Fab")
		)
		(fp_text user "3"
			(at -1.778 5.13207 0)
			(unlocked yes)
			(layer "F.SilkS")
			(effects
				(font
					(size 0.7874 0.5842)
					(thickness 0.1524)
				)
			)
		)
		(fp_text user "1"
			(at -1.477264 0.136398 0)
			(unlocked yes)
			(layer "B.SilkS")
			(effects
				(font
					(size 0.7874 0.5842)
					(thickness 0.1524)
				)
				(justify mirror)
			)
		)
		(fp_text user "3"
			(at -1.411732 5.289296 0)
			(unlocked yes)
			(layer "B.SilkS")
			(effects
				(font
					(size 0.7874 0.5842)
					(thickness 0.1524)
				)
				(justify mirror)
			)
		)
		(fp_text user "3"
			(at -1.1557 5.18287 0)
			(unlocked yes)
			(layer "B.Fab")
			(effects
				(font
					(size 0.7874 0.5842)
					(thickness 0.1524)
				)
				(justify mirror)
			)
		)
		(fp_text user "1"
			(at -1.143 0.02667 0)
			(unlocked yes)
			(layer "B.Fab")
			(effects
				(font
					(size 0.7874 0.5842)
					(thickness 0.1524)
				)
				(justify mirror)
			)
		)
		(fp_text user "3"
			(at -1.778 5.13207 0)
			(unlocked yes)
			(layer "F.Fab")
			(effects
				(font
					(size 0.7874 0.5842)
					(thickness 0.1524)
				)
			)
		)
		(pad "1" thru_hole rect
			(at 0 0)
			(size 1.5494 1.5494)
			(drill 1.0414)
			(layers "*.Cu" "*.Mask")
			(remove_unused_layers no)
			(net "SMB_SML1_PMBUS_HSC_R1_SCL")
			(clearance 0)
			(padstack
				(mode front_inner_back)
				(layer "Inner"
					(shape circle)
					(size 1.5494 1.5494)
					(clearance 0)
				)
				(layer "B.Cu"
					(shape rect)
					(size 1.5494 1.5494)
					(clearance 0)
				)
			)
		)
		(pad "2" thru_hole circle
			(at 0 2.54)
			(size 1.5494 1.5494)
			(drill 1.0414)
			(layers "*.Cu" "*.Mask")
			(remove_unused_layers no)
			(net "SMB_SML1_PMBUS_HSC_R1_SDA")
			(clearance 0)
		)
		(pad "3" thru_hole circle
			(at 0 5.08)
			(size 1.5494 1.5494)
			(drill 1.0414)
			(layers "*.Cu" "*.Mask")
			(remove_unused_layers no)
			(net "GND")
			(clearance 0)
		)
	)
)
